# BASEBOARD_FAB2 (Tioga Pass) — schematic netlist excerpt (pin names and nets, part order shuffled) for the footprints in the layout excerpt that follows; sources: Cadence DE-HDL packaged netlist, KiCad conversion of Wiwynn_Tioga_Pass_MB.brd

R3W4  47KR2F-GP  1%  pkg RCL_GP  page 249 : \1\ = FM_TPM_PRES_RST_N ; \2\ = FM_TPM_PRES_RST_N_R
R25W144  RES  0.0 5% CHIP  pkg 0402  page 145 : A = FM_PWR_BTN_R1_N ; B = FM_PWR_BTN_N
C3M29  CAP_A  1.0UF 6.3V 10% X6S  pkg 0402V  page 127 : A = P1V05_PCH_STBY_ISCLK_PLL ; B = GND

(kicad_pcb
	(version 20260206)
	(generator "pcbnew")
	(generator_version "10.0")
	(general
		(thickness 1.6)
		(legacy_teardrops no)
	)
	(paper "A4")
	(title_block
		(title "Wiwynn_Tioga_Pass_MB.brd")
		(comment 1 "Tioga Pass / footprints 3293-3295 of 4770")
	)
	(layers
		(0 "F.Cu" signal "TOP")
		(4 "In1.Cu" signal "L2GND")
		(6 "In2.Cu" signal "L3")
		(8 "In3.Cu" signal "L4GND")
		(10 "In4.Cu" signal "L5")
		(12 "In5.Cu" signal "L6GND")
		(14 "In6.Cu" signal "L7VCC")
		(16 "In7.Cu" signal "L8VCC")
		(18 "In8.Cu" signal "L9GND")
		(20 "In9.Cu" signal "L10")
		(22 "In10.Cu" signal "L11GND")
		(24 "In11.Cu" signal "L12")
		(26 "In12.Cu" signal "L13GND")
		(2 "B.Cu" signal "BOTTOM")
		(9 "F.Adhes" user "F.Adhesive")
		(11 "B.Adhes" user "B.Adhesive")
		(13 "F.Paste" user "Package Geometry/Pastemask Top")
		(15 "B.Paste" user "Package Geometry/Pastemask Bottom")
		(5 "F.SilkS" user "Ref Des/Silkscreen Top")
		(7 "B.SilkS" user "Ref Des/Silkscreen Bottom")
		(1 "F.Mask" user "Board Geometry/Soldermask Top")
		(3 "B.Mask" user "Board Geometry/Soldermask Bottom")
		(17 "Dwgs.User" user "User.Drawings")
		(19 "Cmts.User" user "User.Comments")
		(21 "Eco1.User" user "User.Eco1")
		(23 "Eco2.User" user "User.Eco2")
		(25 "Edge.Cuts" user "Board Geometry/Outline")
		(27 "Margin" user)
		(31 "F.CrtYd" user "Package Geometry/Place Bound Top")
		(29 "B.CrtYd" user "Package Geometry/Place Bound Bottom")
		(35 "F.Fab" user "Ref Des/Assembly Top")
		(33 "B.Fab" user "Ref Des/Assembly Bottom")
	)
	(footprint ""
		(layer "B.Cu")
		(at 375.0564 -131.9784 180)
		(property "Reference" "C3M29"
			(at 0 0 0)
			(layer "B.SilkS")
			(hide yes)
			(effects
				(font
					(size 1.27 1.27)
				)
				(justify mirror)
			)
		)
		(property "Value" ""
			(at 0 0 0)
			(layer "B.Fab")
			(effects
				(font
					(size 1.27 1.27)
				)
				(justify mirror)
			)
		)
		(duplicate_pad_numbers_are_jumpers no)
		(fp_poly
			(pts
				(xy -0.3048 -0.1016) (xy -0.3048 0.9906) (xy 0.3048 0.9906) (xy 0.3048 -0.1016)
			)
			(stroke
				(width 0)
				(type default)
			)
			(fill no)
			(layer "B.CrtYd")
		)
		(fp_line
			(start 0.3048 0.9906)
			(end -0.3048 0.9906)
			(stroke
				(width 0.1)
				(type default)
			)
			(layer "B.Fab")
		)
		(fp_line
			(start 0.3048 -0.1016)
			(end 0.3048 0.9906)
			(stroke
				(width 0.1)
				(type default)
			)
			(layer "B.Fab")
		)
		(fp_line
			(start -0.3048 0.9906)
			(end -0.3048 -0.1016)
			(stroke
				(width 0.1)
				(type default)
			)
			(layer "B.Fab")
		)
		(fp_line
			(start -0.3048 -0.1016)
			(end 0.3048 -0.1016)
			(stroke
				(width 0.1)
				(type default)
			)
			(layer "B.Fab")
		)
		(pad "1" smd rect
			(at 0 0)
			(size 0.508 0.508)
			(layers "B.Cu" "B.Mask" "B.Paste")
			(net "P1V05_PCH_STBY_ISCLK_PLL")
		)
		(pad "2" smd rect
			(at 0 0.889)
			(size 0.508 0.508)
			(layers "B.Cu" "B.Mask" "B.Paste")
			(net "GND")
		)
		(zone
			(layer "B.Cu")
			(hatch none 0.5)
			(connect_pads
				(clearance 0)
			)
			(min_thickness 0.25)
			(keepout
				(tracks not_allowed)
				(vias allowed)
				(pads allowed)
				(copperpour not_allowed)
				(footprints allowed)
			)
			(placement
				(enabled no)
				(sheetname "")
			)
			(fill
				(thermal_gap 0.5)
				(thermal_bridge_width 0.5)
				(island_removal_mode 0)
			)
			(polygon
				(pts
					(xy 374.8024 -132.6134) (xy 375.3104 -132.6134) (xy 375.3104 -132.2324) (xy 374.8024 -132.2324)
				)
			)
		)
		(zone
			(layer "B.Cu")
			(hatch none 0.5)
			(connect_pads
				(clearance 0)
			)
			(min_thickness 0.25)
			(keepout
				(tracks allowed)
				(vias not_allowed)
				(pads allowed)
				(copperpour not_allowed)
				(footprints allowed)
			)
			(placement
				(enabled no)
				(sheetname "")
			)
			(fill
				(thermal_gap 0.5)
				(thermal_bridge_width 0.5)
				(island_removal_mode 0)
			)
			(polygon
				(pts
					(xy 374.8024 -132.2324) (xy 375.3104 -132.2324) (xy 375.3104 -132.6134) (xy 374.8024 -132.6134)
				)
			)
		)
	)
	(footprint ""
		(layer "B.Cu")
		(at 405.44496 -50.9397 90)
		(property "Reference" "R25W144"
			(at 0.8382 -0.67818 90)
			(unlocked yes)
			(layer "B.SilkS")
			(effects
				(font
					(size 0.4064 0.254)
					(thickness 0.1524)
				)
				(justify left mirror)
			)
		)
		(property "Value" ""
			(at 0 0 90)
			(layer "B.Fab")
			(effects
				(font
					(size 1.27 1.27)
				)
				(justify mirror)
			)
		)
		(duplicate_pad_numbers_are_jumpers no)
		(fp_poly
			(pts
				(xy 0.2794 -0.1016) (xy -0.2794 -0.1016) (xy -0.2794 0.9906) (xy 0.2794 0.9906)
			)
			(stroke
				(width 0)
				(type default)
			)
			(fill no)
			(layer "B.CrtYd")
		)
		(fp_line
			(start 0.2794 -0.1016)
			(end 0.2794 0.9906)
			(stroke
				(width 0.1)
				(type default)
			)
			(layer "B.Fab")
		)
		(fp_line
			(start -0.2794 -0.1016)
			(end 0.2794 -0.1016)
			(stroke
				(width 0.1)
				(type default)
			)
			(layer "B.Fab")
		)
		(fp_line
			(start 0.2794 0.9906)
			(end -0.2794 0.9906)
			(stroke
				(width 0.1)
				(type default)
			)
			(layer "B.Fab")
		)
		(fp_line
			(start -0.2794 0.9906)
			(end -0.2794 -0.1016)
			(stroke
				(width 0.1)
				(type default)
			)
			(layer "B.Fab")
		)
		(pad "1" smd rect
			(at 0 0 270)
			(size 0.508 0.508)
			(layers "B.Cu" "B.Mask" "B.Paste")
			(net "FM_PWR_BTN_R1_N")
		)
		(pad "2" smd rect
			(at 0 0.889 270)
			(size 0.508 0.508)
			(layers "B.Cu" "B.Mask" "B.Paste")
			(net "FM_PWR_BTN_N")
		)
		(zone
			(layer "B.Cu")
			(hatch none 0.5)
			(connect_pads
				(clearance 0)
			)
			(min_thickness 0.25)
			(keepout
				(tracks allowed)
				(vias not_allowed)
				(pads allowed)
				(copperpour not_allowed)
				(footprints allowed)
			)
			(placement
				(enabled no)
				(sheetname "")
			)
			(fill
				(thermal_gap 0.5)
				(thermal_bridge_width 0.5)
				(island_removal_mode 0)
			)
			(polygon
				(pts
					(xy 405.69896 -51.1937) (xy 405.69896 -50.6857) (xy 406.07996 -50.6857) (xy 406.07996 -51.1937)
				)
			)
		)
		(zone
			(layer "B.Cu")
			(hatch none 0.5)
			(connect_pads
				(clearance 0)
			)
			(min_thickness 0.25)
			(keepout
				(tracks not_allowed)
				(vias allowed)
				(pads allowed)
				(copperpour not_allowed)
				(footprints allowed)
			)
			(placement
				(enabled no)
				(sheetname "")
			)
			(fill
				(thermal_gap 0.5)
				(thermal_bridge_width 0.5)
				(island_removal_mode 0)
			)
			(polygon
				(pts
					(xy 406.07996 -51.1937) (xy 406.07996 -50.6857) (xy 405.69896 -50.6857) (xy 405.69896 -51.1937)
				)
			)
		)
	)
	(footprint ""
		(layer "B.Cu")
		(at 442.9506 -22.3393 90)
		(property "Reference" "R3W4"
			(at 0 0 90)
			(layer "B.SilkS")
			(hide yes)
			(effects
				(font
					(size 1.27 1.27)
				)
				(justify mirror)
			)
		)
		(property "Value" "*"
			(at -0.064008 -4.108196 90)
			(unlocked yes)
			(layer "B.Fab")
			(hide yes)
			(effects
				(font
					(size 1.27 1.016)
					(thickness 0.1524)
				)
				(justify mirror)
			)
		)
		(property "Device Type" "47KR2F-GP_RCL_GP-47KR2F-GP,64.A"
			(at -0.064008 -5.632196 90)
			(unlocked yes)
			(layer "B.Fab")
			(hide yes)
			(effects
				(font
					(size 1.27 1.016)
					(thickness 0.1524)
				)
				(justify mirror)
			)
		)
		(duplicate_pad_numbers_are_jumpers no)
		(fp_line
			(start 0.508 -0.9398)
			(end 0.508 0.9398)
			(stroke
				(width 0.1524)
				(type default)
			)
			(layer "B.SilkS")
		)
		(fp_line
			(start -0.508 -0.9398)
			(end 0.508 -0.9398)
			(stroke
				(width 0.1524)
				(type default)
			)
			(layer "B.SilkS")
		)
		(fp_rect
			(start 0.508 0.9398)
			(end -0.508 -0.9398)
			(stroke
				(width 0)
				(type default)
			)
			(fill no)
			(layer "B.CrtYd")
		)
		(fp_rect
			(start 0.508 0.9398)
			(end -0.508 -0.9398)
			(stroke
				(width 0)
				(type default)
			)
			(fill no)
			(layer "B.Fab")
		)
		(pad "1" smd custom
			(at 0 -0.4445 270)
			(size 0.1397 0.1397)
			(layers "B.Cu" "B.Mask" "B.Paste")
			(net "FM_TPM_PRES_RST_N")
			(options
				(clearance outline)
				(anchor circle)
			)
			(primitives
				(gr_poly
					(pts
						(arc
							(start -0.1778 0.2794)
							(mid -0.249642 0.249642)
							(end -0.2794 0.1778)
						)
						(arc
							(start -0.2794 -0.1778)
							(mid -0.249642 -0.249642)
							(end -0.1778 -0.2794)
						)
						(arc
							(start 0.1778 -0.2794)
							(mid 0.249642 -0.249642)
							(end 0.2794 -0.1778)
						)
						(arc
							(start 0.2794 0.1778)
							(mid 0.249642 0.249642)
							(end 0.1778 0.2794)
						)
					)
					(width 0)
					(fill yes)
				)
			)
		)
		(pad "2" smd custom
			(at 0 0.4445 270)
			(size 0.1397 0.1397)
			(layers "B.Cu" "B.Mask" "B.Paste")
			(net "FM_TPM_PRES_RST_N_R")
			(options
				(clearance outline)
				(anchor circle)
			)
			(primitives
				(gr_poly
					(pts
						(arc
							(start -0.1778 0.2794)
							(mid -0.249642 0.249642)
							(end -0.2794 0.1778)
						)
						(arc
							(start -0.2794 -0.1778)
							(mid -0.249642 -0.249642)
							(end -0.1778 -0.2794)
						)
						(arc
							(start 0.1778 -0.2794)
							(mid 0.249642 -0.249642)
							(end 0.2794 -0.1778)
						)
						(arc
							(start 0.2794 0.1778)
							(mid 0.249642 0.249642)
							(end 0.1778 0.2794)
						)
					)
					(width 0)
					(fill yes)
				)
			)
		)
	)
)
